FILE_TYPE = MULTI_PHYS_TABLE;

PART 'SCONN60_ASP21410801'

{========================================================================================}
:VALUE                   | PART_TYPE | MATERIAL | PART_NUMBER    = STANDARD        | LIFECYCLE      | PART_NUMBER   | JEDEC_TYPE               | DESCRIPTION                              | MANUFTR | MANUF_PN        | RD_CMPLS_LVL | CMPLS_LVL | CLASS | DIP_SMD | FROM_PJ    | DATA                    | FP_ECN              | EE_CHECK_LIST | CREATOR | CREATEDAY  | PSL | STATUS | ESD_CDM | ESD_HBM | ESD_MM | MSD  | PIN_LENGTH_LONG_PIN | PIN_LENGTH_SHORT_PIN ;
{========================================================================================}
 'SCONN60_ASP-214108-01' | 'SMLF'    | 'IO'     | 'DFHS60FS108'(!) = ''               | ''               | 'DFHS60FS108' |'CON_60S2H2D4S_P0-5_LDV'| 'CONN SMD HOUSING 60P 2R FS(P0.5,H3.05)' | 'STC'   | 'ASP-214108-01' | 'EP(V1)'     | 'EP(V1)'  | 'IO'  | ''      | 'F0C-IVES' | 'STC_ASP-214108-01.pdf' | 'ASP-214108-01.msg' | ''            | ''      | '20210127' | ''  | ''     | '0'     | '0'     | '0'    | 'NA' | '30 MILS'           | '30 MILS'           
 'SCONN60_ASP-214108-01' | 'SMLF'    | 'EMPTY'  | 'DFHS60FS108'(!) = ''               | ''               | 'DFHS60FS108' |'CON_60S2H2D4S_P0-5_LDV'| 'CONN SMD HOUSING 60P 2R FS(P0.5,H3.05)' | 'STC'   | 'ASP-214108-01' | 'EP(V1)'     | 'EP(V1)'  | 'IO'  | ''      | 'F0C-IVES' | 'STC_ASP-214108-01.pdf' | 'ASP-214108-01.msg' | ''            | ''      | '20210127' | ''  | ''     | '0'     | '0'     | '0'    | 'NA' | '30 MILS'           | '30 MILS'           

END_PART

END.

